FILE_TYPE = MACRO_DRAWING;
SET COLOR_WIRE YELLOW;
SET COLOR_PROP ORANGE;
SET COLOR_DOT WHITE;
SET COLOR_ARC YELLOW;
SET COLOR_BODY GREEN;
SET COLOR_NOTE PURPLE;
SET PROP_DISPLAY VALUE;
SET PAGE_NUMBER P1;
FORCEADD SYNONYM..1
(1850 2050);
PAINT MONO (1850 2050);
FORCEPROP 2 LAST PATH 4P
J 0
(1850 2150);
DISPLAY 0.872340 (1850 2150);
PAINT YELLOW (1850 2150);
FORCEPROP 1 LAST NEEDS_NO_SIZE TRUE
J 0
(1875 2125);
DISPLAY 0.872340 (1875 2125);
PAINT MONO (1875 2125);
DISPLAY INVISIBLE (1875 2125);
FORCEPROP 1 LAST BODY_TYPE PLUMBING
J 0
(1850 2100);
DISPLAY 0.872340 (1850 2100);
PAINT GREEN (1850 2100);
DISPLAY INVISIBLE (1850 2100);
FORCEPROP 2 LAST CDS_LIB mstr_standard
J 0
(1850 2050);
DISPLAY 0.851064 (1850 2050);
DISPLAY INVISIBLE (1850 2050);
FORCEADD DRAWING..2
(1275 1750);
PAINT MONO (1275 1750);
FORCEPROP 1 LAST LAST_MODIFIED Tue Oct 25 14:31:39 2011
J 0
(1575 1500);
DISPLAY 0.872340 (1575 1500);
PAINT GREEN (1575 1500);
FORCEPROP 1 LAST TITLE P5V_STBY
J 0
(1325 1700);
DISPLAY 0.872340 (1325 1700);
PAINT GREEN (1325 1700);
FORCEPROP 1 LAST ABBREV P5V_STBY
J 0
(1325 1650);
DISPLAY 0.872340 (1325 1650);
PAINT GREEN (1325 1650);
WIRE 0 -1 (1900 2050)(2050 2050);
FORCEPROP 2 LAST SIG_NAME P5V_STBY \G
J 0
(2075 2085);
DISPLAY 0.872340 (2075 2085);
PAINT MONO (2075 2085);
WIRE 16 -1 (1800 2050)(1200 2050);
FORCEPROP 2 LAST SIG_NAME G\I
J 0
(1025 2060);
DISPLAY 0.872340 (1025 2060);
PAINT MONO (1025 2060);
QUIT
